# TIMECARD (Time Appliance Project (Time Card)) — schematic netlist excerpt (pin names and nets, part order shuffled) for the footprints in the layout excerpt that follows; sources: Cadence DE-HDL packaged netlist, KiCad conversion of R4006-B0001-02_R01.brd

L2  INDUCTOR_2  4.7UH 20%  pkg SMC_L_287X268_V3  page 28 : \1\ = XP3R3V_SW ; \2\ = XP3R3V
C53  CAPACITOR  0.1UF 25V 10%  pkg SMC_0402R_H022  page 28 : \1\ = VIN_XP3R3 ; \2\ = SG

(kicad_pcb
	(version 20260206)
	(generator "pcbnew")
	(generator_version "10.0")
	(general
		(thickness 1.6)
		(legacy_teardrops no)
	)
	(paper "A4")
	(title_block
		(title "timecard-production-celestica-r4006 — R4006-B0001-02_R01.brd")
		(comment 1 "Time Appliance Project (Time Card) / footprints 407-409 of 1113")
	)
	(layers
		(0 "F.Cu" signal "TOP")
		(4 "In1.Cu" signal "L02_GND1")
		(6 "In2.Cu" signal "L03_SIG1")
		(8 "In3.Cu" signal "L04_GND2")
		(10 "In4.Cu" signal "L05_VCC1")
		(12 "In5.Cu" signal "L06_VCC2")
		(14 "In6.Cu" signal "L07_GND3")
		(16 "In7.Cu" signal "L08_SIG2")
		(18 "In8.Cu" signal "L09_GND4")
		(2 "B.Cu" signal "BOTTOM")
		(9 "F.Adhes" user "F.Adhesive")
		(11 "B.Adhes" user "B.Adhesive")
		(13 "F.Paste" user "Package Geometry/Pastemask Top")
		(15 "B.Paste" user "Package Geometry/Pastemask Bottom")
		(5 "F.SilkS" user "Ref Des/Silkscreen Top")
		(7 "B.SilkS" user "Ref Des/Silkscreen Bottom")
		(1 "F.Mask" user "Board Geometry/Soldermask Top")
		(3 "B.Mask" user "Board Geometry/Soldermask Bottom")
		(17 "Dwgs.User" user "User.Drawings")
		(19 "Cmts.User" user "User.Comments")
		(21 "Eco1.User" user "User.Eco1")
		(23 "Eco2.User" user "User.Eco2")
		(25 "Edge.Cuts" user "Board Geometry/Outline")
		(27 "Margin" user)
		(31 "F.CrtYd" user "Package Geometry/Place Bound Top")
		(29 "B.CrtYd" user "Package Geometry/Place Bound Bottom")
		(35 "F.Fab" user "Ref Des/Assembly Top")
		(33 "B.Fab" user "Ref Des/Assembly Bottom")
	)
	(footprint ""
		(layer "F.Cu")
		(at 77.47 -98.171 -90)
		(property "Reference" "L2"
			(at 0.127 5.04063 90)
			(unlocked yes)
			(layer "F.SilkS")
			(effects
				(font
					(size 0.7874 0.5842)
					(thickness 0.1524)
				)
			)
		)
		(property "Value" "VAL*"
			(at -0.035306 8.510778 270)
			(unlocked yes)
			(layer "F.Fab")
			(hide yes)
			(effects
				(font
					(size 0.7874 0.5842)
					(thickness 0.1524)
				)
			)
		)
		(property "Tolerance" "TOL*"
			(at -0.061722 7.222744 270)
			(unlocked yes)
			(layer "Cmts.User")
			(hide yes)
			(effects
				(font
					(size 0.7874 0.5842)
					(thickness 0.1524)
				)
			)
		)
		(property "User Part Number" "PARTNUM*"
			(at 0 6.106668 270)
			(unlocked yes)
			(layer "Cmts.User")
			(hide yes)
			(effects
				(font
					(size 0.7874 0.5842)
					(thickness 0.1524)
				)
			)
		)
		(property "Device Type" "INDUCTOR_2-G190-10424-01,4.7UHA"
			(at 0 4.912868 270)
			(unlocked yes)
			(layer "F.Fab")
			(hide yes)
			(effects
				(font
					(size 0.7874 0.5842)
					(thickness 0.1524)
				)
			)
		)
		(duplicate_pad_numbers_are_jumpers no)
		(fp_line
			(start -4.448302 3.803904)
			(end -4.448302 -3.803904)
			(stroke
				(width 0.1)
				(type default)
			)
			(layer "F.SilkS")
		)
		(fp_line
			(start 4.448302 3.803904)
			(end -4.448302 3.803904)
			(stroke
				(width 0.1)
				(type default)
			)
			(layer "F.SilkS")
		)
		(fp_line
			(start -4.448302 -3.803904)
			(end 4.448302 -3.803904)
			(stroke
				(width 0.1)
				(type default)
			)
			(layer "F.SilkS")
		)
		(fp_line
			(start 4.448302 -3.803904)
			(end 4.448302 3.803904)
			(stroke
				(width 0.1)
				(type default)
			)
			(layer "F.SilkS")
		)
		(fp_rect
			(start 4.702302 -4.057904)
			(end -4.702302 4.057904)
			(stroke
				(width 0)
				(type default)
			)
			(fill no)
			(layer "F.CrtYd")
		)
		(fp_line
			(start -3.800094 3.549904)
			(end -3.800094 -3.549904)
			(stroke
				(width 0.1)
				(type default)
			)
			(layer "F.Fab")
		)
		(fp_line
			(start 3.800094 3.549904)
			(end -3.800094 3.549904)
			(stroke
				(width 0.1)
				(type default)
			)
			(layer "F.Fab")
		)
		(fp_line
			(start -3.800094 -3.549904)
			(end 3.800094 -3.549904)
			(stroke
				(width 0.1)
				(type default)
			)
			(layer "F.Fab")
		)
		(fp_line
			(start 3.800094 -3.549904)
			(end 3.800094 3.549904)
			(stroke
				(width 0.1)
				(type default)
			)
			(layer "F.Fab")
		)
		(fp_text user "1"
			(at -5.42163 0 0)
			(unlocked yes)
			(layer "F.SilkS")
			(effects
				(font
					(size 0.7874 0.5842)
					(thickness 0.1524)
				)
			)
		)
		(fp_text user "2"
			(at 5.50037 -0.254 0)
			(unlocked yes)
			(layer "F.SilkS")
			(effects
				(font
					(size 0.7874 0.5842)
					(thickness 0.1524)
				)
			)
		)
		(fp_text user "1"
			(at -4.67233 0 0)
			(unlocked yes)
			(layer "F.Fab")
			(effects
				(font
					(size 0.7874 0.5842)
					(thickness 0.1524)
				)
			)
		)
		(fp_text user "2"
			(at 4.59867 0 0)
			(unlocked yes)
			(layer "F.Fab")
			(effects
				(font
					(size 0.7874 0.5842)
					(thickness 0.1524)
				)
			)
		)
		(pad "1" smd rect
			(at -2.975102 0 270)
			(size 2.4384 3.7084)
			(layers "F.Cu" "F.Mask" "F.Paste")
			(net "XP3R3V_SW")
		)
		(pad "2" smd rect
			(at 2.975102 0 270)
			(size 2.4384 3.7084)
			(layers "F.Cu" "F.Mask" "F.Paste")
			(net "XP3R3V")
		)
		(zone
			(layer "F.Cu")
			(hatch none 0.5)
			(connect_pads
				(clearance 0)
			)
			(min_thickness 0.25)
			(keepout
				(tracks allowed)
				(vias not_allowed)
				(pads allowed)
				(copperpour not_allowed)
				(footprints allowed)
			)
			(placement
				(enabled no)
				(sheetname "")
			)
			(fill
				(thermal_gap 0.5)
				(thermal_bridge_width 0.5)
				(island_removal_mode 0)
			)
			(polygon
				(pts
					(xy 73.920096 -101.971094) (xy 75.6158 -101.971094) (xy 75.6158 -99.926902) (xy 79.3242 -99.926902)
					(xy 79.3242 -101.971094) (xy 81.019904 -101.971094) (xy 81.019904 -94.370906) (xy 79.3242 -94.370906)
					(xy 79.3242 -96.415098) (xy 75.6158 -96.415098) (xy 75.6158 -94.370906) (xy 73.920096 -94.370906)
				)
			)
		)
	)
	(footprint ""
		(layer "F.Cu")
		(at 48.768 -122.555)
		(property "Reference" "SP77"
			(at 0 0 0)
			(layer "F.SilkS")
			(hide yes)
			(effects
				(font
					(size 1.27 1.27)
				)
			)
		)
		(property "Value" ""
			(at 0 0 0)
			(layer "F.Fab")
			(effects
				(font
					(size 1.27 1.27)
				)
			)
		)
		(duplicate_pad_numbers_are_jumpers no)
	)
	(footprint ""
		(layer "F.Cu")
		(at 84.0232 -105.0798 180)
		(property "Reference" "C53"
			(at 2.794 -0.16637 0)
			(unlocked yes)
			(layer "F.SilkS")
			(effects
				(font
					(size 0.7874 0.5842)
					(thickness 0.1524)
				)
			)
		)
		(property "Value" "VAL*"
			(at 0.0762 2.067306 180)
			(unlocked yes)
			(layer "F.Fab")
			(hide yes)
			(effects
				(font
					(size 0.7874 0.5842)
					(thickness 0.1524)
				)
			)
		)
		(property "Tolerance" "TOL*"
			(at 0.0762 3.032506 180)
			(unlocked yes)
			(layer "Cmts.User")
			(hide yes)
			(effects
				(font
					(size 0.7874 0.5842)
					(thickness 0.1524)
				)
			)
		)
		(property "User Part Number" "PARTNUM*"
			(at 0.1016 4.023106 180)
			(unlocked yes)
			(layer "Cmts.User")
			(hide yes)
			(effects
				(font
					(size 0.7874 0.5842)
					(thickness 0.1524)
				)
			)
		)
		(property "Device Type" "CAPACITOR-G105-0B104-EK,0.1UF,A"
			(at 0.0508 1.127506 180)
			(unlocked yes)
			(layer "F.Fab")
			(hide yes)
			(effects
				(font
					(size 0.7874 0.5842)
					(thickness 0.1524)
				)
			)
		)
		(duplicate_pad_numbers_are_jumpers no)
		(fp_line
			(start 1.143 0.5588)
			(end 1.143 -0.5588)
			(stroke
				(width 0.1)
				(type default)
			)
			(layer "F.SilkS")
		)
		(fp_line
			(start 1.143 -0.5588)
			(end -1.143 -0.5588)
			(stroke
				(width 0.1)
				(type default)
			)
			(layer "F.SilkS")
		)
		(fp_line
			(start -1.143 0.5588)
			(end 1.143 0.5588)
			(stroke
				(width 0.1)
				(type default)
			)
			(layer "F.SilkS")
		)
		(fp_line
			(start -1.143 -0.5588)
			(end -1.143 0.5588)
			(stroke
				(width 0.1)
				(type default)
			)
			(layer "F.SilkS")
		)
		(fp_rect
			(start 1.143 -0.5588)
			(end -1.143 0.5588)
			(stroke
				(width 0)
				(type default)
			)
			(fill no)
			(layer "F.CrtYd")
		)
		(fp_line
			(start 0.508 0.3048)
			(end 0.508 -0.3048)
			(stroke
				(width 0.1)
				(type default)
			)
			(layer "F.Fab")
		)
		(fp_line
			(start 0.508 -0.3048)
			(end -0.508 -0.3048)
			(stroke
				(width 0.1)
				(type default)
			)
			(layer "F.Fab")
		)
		(fp_line
			(start -0.508 0.3048)
			(end 0.508 0.3048)
			(stroke
				(width 0.1)
				(type default)
			)
			(layer "F.Fab")
		)
		(fp_line
			(start -0.508 -0.3048)
			(end -0.508 0.3048)
			(stroke
				(width 0.1)
				(type default)
			)
			(layer "F.Fab")
		)
		(pad "1" smd rect
			(at -0.5334 0 180)
			(size 0.7112 0.6096)
			(layers "F.Cu" "F.Mask" "F.Paste")
			(net "VIN_XP3R3")
		)
		(pad "2" smd rect
			(at 0.5334 0 180)
			(size 0.7112 0.6096)
			(layers "F.Cu" "F.Mask" "F.Paste")
			(net "SG")
		)
		(zone
			(layer "F.Cu")
			(hatch none 0.5)
			(connect_pads
				(clearance 0)
			)
			(min_thickness 0.25)
			(keepout
				(tracks allowed)
				(vias not_allowed)
				(pads allowed)
				(copperpour not_allowed)
				(footprints allowed)
			)
			(placement
				(enabled no)
				(sheetname "")
			)
			(fill
				(thermal_gap 0.5)
				(thermal_bridge_width 0.5)
				(island_removal_mode 0)
			)
			(polygon
				(pts
					(xy 83.947 -104.775) (xy 84.0994 -104.775) (xy 84.0994 -105.3846) (xy 83.947 -105.3846)
				)
			)
		)
	)
)
